FILE_TYPE = CONNECTIVITY;
{Allegro Design Entry HDL 17.4-2019 S026 (4007227) 1/17/2022}
"PAGE_NUMBER" = 145;
0"NC";
END.
